(kicad_pcb
	(version 20260206)
	(generator "pcbnew")
	(generator_version "10.0")
	(general
		(thickness 1.6)
		(legacy_teardrops no)
	)
	(paper "A4")
	(title_block
		(title "Bryce Canyon_F.DPB_16315-1-OCP.brd")
		(comment 1 "Bryce Canyon / footprints 202-209 of 2223")
	)
	(layers
		(0 "F.Cu" signal "TOP")
		(4 "In1.Cu" signal "L2GND")
		(6 "In2.Cu" signal "L3")
		(8 "In3.Cu" signal "L4GND")
		(10 "In4.Cu" signal "L5")
		(12 "In5.Cu" signal "L6VCC")
		(14 "In6.Cu" signal "L7VCC")
		(16 "In7.Cu" signal "L8")
		(18 "In8.Cu" signal "L9GND")
		(20 "In9.Cu" signal "L10")
		(22 "In10.Cu" signal "L11GND")
		(2 "B.Cu" signal "BOTTOM")
		(9 "F.Adhes" user "F.Adhesive")
		(11 "B.Adhes" user "B.Adhesive")
		(13 "F.Paste" user "Package Geometry/Pastemask Top")
		(15 "B.Paste" user "Package Geometry/Pastemask Bottom")
		(5 "F.SilkS" user "Ref Des/Silkscreen Top")
		(7 "B.SilkS" user "Ref Des/Silkscreen Bottom")
		(1 "F.Mask" user "Board Geometry/Soldermask Top")
		(3 "B.Mask" user "Board Geometry/Soldermask Bottom")
		(17 "Dwgs.User" user "User.Drawings")
		(19 "Cmts.User" user "User.Comments")
		(21 "Eco1.User" user "User.Eco1")
		(23 "Eco2.User" user "User.Eco2")
		(25 "Edge.Cuts" user "Board Geometry/Outline")
		(27 "Margin" user)
		(31 "F.CrtYd" user "Package Geometry/Place Bound Top")
		(29 "B.CrtYd" user "Package Geometry/Place Bound Bottom")
		(35 "F.Fab" user "Ref Des/Assembly Top")
		(33 "B.Fab" user "Ref Des/Assembly Bottom")
	)
	(footprint ""
		(layer "F.Cu")
		(at 443.068202 -253.42215 -90)
		(property "Reference" "R1257"
			(at 0 0 270)
			(layer "F.SilkS")
			(hide yes)
			(effects
				(font
					(size 1.27 1.27)
				)
			)
		)
		(property "Value" "309KR2F-GP"
			(at 0.064008 -3.993896 270)
			(unlocked yes)
			(layer "F.Fab")
			(hide yes)
			(effects
				(font
					(size 1.016 1.016)
					(thickness 0.1524)
				)
			)
		)
		(property "Device Type" "R402H16"
			(at 0.064008 -5.517896 270)
			(unlocked yes)
			(layer "F.Fab")
			(hide yes)
			(effects
				(font
					(size 1.016 1.016)
					(thickness 0.1524)
				)
			)
		)
		(duplicate_pad_numbers_are_jumpers no)
		(fp_line
			(start -0.508 -0.9398)
			(end -0.508 0.9398)
			(stroke
				(width 0.1524)
				(type default)
			)
			(layer "F.SilkS")
		)
		(fp_line
			(start 0.508 -0.9398)
			(end -0.508 -0.9398)
			(stroke
				(width 0.1524)
				(type default)
			)
			(layer "F.SilkS")
		)
		(fp_rect
			(start -0.508 0.9398)
			(end 0.508 -0.9398)
			(stroke
				(width 0)
				(type default)
			)
			(fill no)
			(layer "F.CrtYd")
		)
		(fp_rect
			(start -0.508 0.9398)
			(end 0.508 -0.9398)
			(stroke
				(width 0)
				(type default)
			)
			(fill no)
			(layer "F.Fab")
		)
		(pad "1" smd custom
			(at 0 -0.4445 270)
			(size 0.1397 0.1397)
			(layers "F.Cu" "F.Mask" "F.Paste")
			(net "P5V_C_RF")
			(options
				(clearance outline)
				(anchor circle)
			)
			(primitives
				(gr_poly
					(pts
						(arc
							(start -0.1778 -0.2794)
							(mid -0.249642 -0.249642)
							(end -0.2794 -0.1778)
						)
						(arc
							(start -0.2794 0.1778)
							(mid -0.249642 0.249642)
							(end -0.1778 0.2794)
						)
						(arc
							(start 0.1778 0.2794)
							(mid 0.249642 0.249642)
							(end 0.2794 0.1778)
						)
						(arc
							(start 0.2794 -0.1778)
							(mid 0.249642 -0.249642)
							(end 0.1778 -0.2794)
						)
					)
					(width 0)
					(fill yes)
				)
			)
		)
		(pad "2" smd custom
			(at 0 0.4445 270)
			(size 0.1397 0.1397)
			(layers "F.Cu" "F.Mask" "F.Paste")
			(net "P5V_C_VREG")
			(options
				(clearance outline)
				(anchor circle)
			)
			(primitives
				(gr_poly
					(pts
						(arc
							(start -0.1778 -0.2794)
							(mid -0.249642 -0.249642)
							(end -0.2794 -0.1778)
						)
						(arc
							(start -0.2794 0.1778)
							(mid -0.249642 0.249642)
							(end -0.1778 0.2794)
						)
						(arc
							(start 0.1778 0.2794)
							(mid 0.249642 0.249642)
							(end 0.2794 0.1778)
						)
						(arc
							(start 0.2794 -0.1778)
							(mid 0.249642 -0.249642)
							(end 0.1778 -0.2794)
						)
					)
					(width 0)
					(fill yes)
				)
			)
		)
	)
	(footprint ""
		(layer "F.Cu")
		(at 32.463486 -44.219368 90)
		(property "Reference" "C350"
			(at 0 0 90)
			(layer "F.SilkS")
			(hide yes)
			(effects
				(font
					(size 1.27 1.27)
				)
			)
		)
		(property "Value" "SCD01U16V1KX-GP"
			(at -2.8321 -1.7399 90)
			(unlocked yes)
			(layer "F.Fab")
			(hide yes)
			(effects
				(font
					(size 1.016 1.016)
					(thickness 0.1524)
				)
			)
		)
		(property "Device Type" "C0201H13"
			(at -2.8321 -3.2639 90)
			(unlocked yes)
			(layer "F.Fab")
			(hide yes)
			(effects
				(font
					(size 1.016 1.016)
					(thickness 0.1524)
				)
			)
		)
		(duplicate_pad_numbers_are_jumpers no)
		(fp_rect
			(start -0.2794 0.6477)
			(end 0.2794 -0.6477)
			(stroke
				(width 0)
				(type default)
			)
			(fill no)
			(layer "F.CrtYd")
		)
		(fp_rect
			(start -0.2794 0.6477)
			(end 0.2794 -0.6477)
			(stroke
				(width 0)
				(type default)
			)
			(fill no)
			(layer "F.Fab")
		)
		(pad "1" smd custom
			(at 0 -0.2794 90)
			(size 0.0762 0.0762)
			(layers "F.Cu" "F.Mask" "F.Paste")
			(net "SAS_HDD_RX_N24")
			(options
				(clearance outline)
				(anchor circle)
			)
			(primitives
				(gr_poly
					(pts
						(arc
							(start 0.1524 -0.127)
							(mid 0.137521 -0.162921)
							(end 0.1016 -0.1778)
						)
						(arc
							(start -0.1016 -0.1778)
							(mid -0.137521 -0.162921)
							(end -0.1524 -0.127)
						)
						(arc
							(start -0.1524 0.127)
							(mid -0.137521 0.162921)
							(end -0.1016 0.1778)
						)
						(arc
							(start 0.1016 0.1778)
							(mid 0.137521 0.162921)
							(end 0.1524 0.127)
						)
					)
					(width 0)
					(fill yes)
				)
			)
		)
		(pad "2" smd custom
			(at 0 0.2794 90)
			(size 0.0762 0.0762)
			(layers "F.Cu" "F.Mask" "F.Paste")
			(net "PHY_SCC_A_TO_DRV_A_24_DN")
			(options
				(clearance outline)
				(anchor circle)
			)
			(primitives
				(gr_poly
					(pts
						(arc
							(start 0.1524 -0.127)
							(mid 0.137521 -0.162921)
							(end 0.1016 -0.1778)
						)
						(arc
							(start -0.1016 -0.1778)
							(mid -0.137521 -0.162921)
							(end -0.1524 -0.127)
						)
						(arc
							(start -0.1524 0.127)
							(mid -0.137521 0.162921)
							(end -0.1016 0.1778)
						)
						(arc
							(start 0.1016 0.1778)
							(mid 0.137521 0.162921)
							(end 0.1524 0.127)
						)
					)
					(width 0)
					(fill yes)
				)
			)
		)
	)
	(footprint ""
		(layer "F.Cu")
		(at 459.4479 -42.585894 180)
		(property "Reference" "R920"
			(at 0 0 180)
			(layer "F.SilkS")
			(hide yes)
			(effects
				(font
					(size 1.27 1.27)
				)
			)
		)
		(property "Value" "1KR2F-3-GP"
			(at 0.064008 -3.993896 180)
			(unlocked yes)
			(layer "F.Fab")
			(hide yes)
			(effects
				(font
					(size 1.016 1.016)
					(thickness 0.1524)
				)
			)
		)
		(property "Device Type" "R402H16"
			(at 0.064008 -5.517896 180)
			(unlocked yes)
			(layer "F.Fab")
			(hide yes)
			(effects
				(font
					(size 1.016 1.016)
					(thickness 0.1524)
				)
			)
		)
		(duplicate_pad_numbers_are_jumpers no)
		(fp_line
			(start 0.508 -0.9398)
			(end -0.508 -0.9398)
			(stroke
				(width 0.1524)
				(type default)
			)
			(layer "F.SilkS")
		)
		(fp_line
			(start -0.508 -0.9398)
			(end -0.508 0.9398)
			(stroke
				(width 0.1524)
				(type default)
			)
			(layer "F.SilkS")
		)
		(fp_rect
			(start -0.508 0.9398)
			(end 0.508 -0.9398)
			(stroke
				(width 0)
				(type default)
			)
			(fill no)
			(layer "F.CrtYd")
		)
		(fp_rect
			(start -0.508 0.9398)
			(end 0.508 -0.9398)
			(stroke
				(width 0)
				(type default)
			)
			(fill no)
			(layer "F.Fab")
		)
		(pad "1" smd custom
			(at 0 -0.4445 180)
			(size 0.1397 0.1397)
			(layers "F.Cu" "F.Mask" "F.Paste")
			(net "P3V3_STBY_A")
			(options
				(clearance outline)
				(anchor circle)
			)
			(primitives
				(gr_poly
					(pts
						(arc
							(start -0.1778 -0.2794)
							(mid -0.249642 -0.249642)
							(end -0.2794 -0.1778)
						)
						(arc
							(start -0.2794 0.1778)
							(mid -0.249642 0.249642)
							(end -0.1778 0.2794)
						)
						(arc
							(start 0.1778 0.2794)
							(mid 0.249642 0.249642)
							(end 0.2794 0.1778)
						)
						(arc
							(start 0.2794 -0.1778)
							(mid 0.249642 -0.249642)
							(end 0.1778 -0.2794)
						)
					)
					(width 0)
					(fill yes)
				)
			)
		)
		(pad "2" smd custom
			(at 0 0.4445 180)
			(size 0.1397 0.1397)
			(layers "F.Cu" "F.Mask" "F.Paste")
			(net "SW_PWR_R_HDD34")
			(options
				(clearance outline)
				(anchor circle)
			)
			(primitives
				(gr_poly
					(pts
						(arc
							(start -0.1778 -0.2794)
							(mid -0.249642 -0.249642)
							(end -0.2794 -0.1778)
						)
						(arc
							(start -0.2794 0.1778)
							(mid -0.249642 0.249642)
							(end -0.1778 0.2794)
						)
						(arc
							(start 0.1778 0.2794)
							(mid 0.249642 0.249642)
							(end 0.2794 0.1778)
						)
						(arc
							(start 0.2794 -0.1778)
							(mid 0.249642 -0.249642)
							(end 0.1778 -0.2794)
						)
					)
					(width 0)
					(fill yes)
				)
			)
		)
	)
	(footprint ""
		(layer "F.Cu")
		(at 255.143 -301.244 180)
		(property "Reference" "R9"
			(at 0 0 180)
			(layer "F.SilkS")
			(hide yes)
			(effects
				(font
					(size 1.27 1.27)
				)
			)
		)
		(property "Value" "10KR2F-2-GP"
			(at 0.064008 -3.993896 180)
			(unlocked yes)
			(layer "F.Fab")
			(hide yes)
			(effects
				(font
					(size 1.016 1.016)
					(thickness 0.1524)
				)
			)
		)
		(property "Device Type" "R402H16"
			(at 0.064008 -5.517896 180)
			(unlocked yes)
			(layer "F.Fab")
			(hide yes)
			(effects
				(font
					(size 1.016 1.016)
					(thickness 0.1524)
				)
			)
		)
		(duplicate_pad_numbers_are_jumpers no)
		(fp_line
			(start 0.508 -0.9398)
			(end -0.508 -0.9398)
			(stroke
				(width 0.1524)
				(type default)
			)
			(layer "F.SilkS")
		)
		(fp_line
			(start -0.508 -0.9398)
			(end -0.508 0.9398)
			(stroke
				(width 0.1524)
				(type default)
			)
			(layer "F.SilkS")
		)
		(fp_rect
			(start -0.508 0.9398)
			(end 0.508 -0.9398)
			(stroke
				(width 0)
				(type default)
			)
			(fill no)
			(layer "F.CrtYd")
		)
		(fp_rect
			(start -0.508 0.9398)
			(end 0.508 -0.9398)
			(stroke
				(width 0)
				(type default)
			)
			(fill no)
			(layer "F.Fab")
		)
		(pad "1" smd custom
			(at 0 -0.4445 180)
			(size 0.1397 0.1397)
			(layers "F.Cu" "F.Mask" "F.Paste")
			(net "EEPROM_WP")
			(options
				(clearance outline)
				(anchor circle)
			)
			(primitives
				(gr_poly
					(pts
						(arc
							(start -0.1778 -0.2794)
							(mid -0.249642 -0.249642)
							(end -0.2794 -0.1778)
						)
						(arc
							(start -0.2794 0.1778)
							(mid -0.249642 0.249642)
							(end -0.1778 0.2794)
						)
						(arc
							(start 0.1778 0.2794)
							(mid 0.249642 0.249642)
							(end 0.2794 0.1778)
						)
						(arc
							(start 0.2794 -0.1778)
							(mid 0.249642 -0.249642)
							(end 0.1778 -0.2794)
						)
					)
					(width 0)
					(fill yes)
				)
			)
		)
		(pad "2" smd custom
			(at 0 0.4445 180)
			(size 0.1397 0.1397)
			(layers "F.Cu" "F.Mask" "F.Paste")
			(net "GND")
			(options
				(clearance outline)
				(anchor circle)
			)
			(primitives
				(gr_poly
					(pts
						(arc
							(start -0.1778 -0.2794)
							(mid -0.249642 -0.249642)
							(end -0.2794 -0.1778)
						)
						(arc
							(start -0.2794 0.1778)
							(mid -0.249642 0.249642)
							(end -0.1778 0.2794)
						)
						(arc
							(start 0.1778 0.2794)
							(mid 0.249642 0.249642)
							(end 0.2794 0.1778)
						)
						(arc
							(start 0.2794 -0.1778)
							(mid 0.249642 -0.249642)
							(end 0.1778 -0.2794)
						)
					)
					(width 0)
					(fill yes)
				)
			)
		)
	)
	(footprint ""
		(layer "F.Cu")
		(at 381.36195 -291.127942 -90)
		(property "Reference" "C149"
			(at 0 0 270)
			(layer "F.SilkS")
			(hide yes)
			(effects
				(font
					(size 1.27 1.27)
				)
			)
		)
		(property "Value" "SCD01U50V2KX-1GP"
			(at 1.1811 -2.7051 270)
			(unlocked yes)
			(layer "F.Fab")
			(hide yes)
			(effects
				(font
					(size 1.016 1.016)
					(thickness 0.1524)
				)
			)
		)
		(property "Device Type" "C402H22"
			(at 1.1811 -4.2291 270)
			(unlocked yes)
			(layer "F.Fab")
			(hide yes)
			(effects
				(font
					(size 1.016 1.016)
					(thickness 0.1524)
				)
			)
		)
		(duplicate_pad_numbers_are_jumpers no)
		(fp_rect
			(start -0.4318 0.9525)
			(end 0.4318 -0.9525)
			(stroke
				(width 0)
				(type default)
			)
			(fill no)
			(layer "F.CrtYd")
		)
		(fp_rect
			(start -0.4318 0.9525)
			(end 0.4318 -0.9525)
			(stroke
				(width 0)
				(type default)
			)
			(fill no)
			(layer "F.Fab")
		)
		(pad "1" smd custom
			(at 0 -0.4445 270)
			(size 0.1524 0.1524)
			(layers "F.Cu" "F.Mask" "F.Paste")
			(net "HDD_PRSNT_8")
			(options
				(clearance outline)
				(anchor circle)
			)
			(primitives
				(gr_poly
					(pts
						(arc
							(start 0.3048 -0.2032)
							(mid 0.275042 -0.275042)
							(end 0.2032 -0.3048)
						)
						(arc
							(start -0.2032 -0.3048)
							(mid -0.275042 -0.275042)
							(end -0.3048 -0.2032)
						)
						(arc
							(start -0.3048 0.2032)
							(mid -0.275042 0.275042)
							(end -0.2032 0.3048)
						)
						(arc
							(start 0.2032 0.3048)
							(mid 0.275042 0.275042)
							(end 0.3048 0.2032)
						)
					)
					(width 0)
					(fill yes)
				)
			)
		)
		(pad "2" smd custom
			(at 0 0.4445 270)
			(size 0.1524 0.1524)
			(layers "F.Cu" "F.Mask" "F.Paste")
			(net "GND")
			(options
				(clearance outline)
				(anchor circle)
			)
			(primitives
				(gr_poly
					(pts
						(arc
							(start 0.3048 -0.2032)
							(mid 0.275042 -0.275042)
							(end 0.2032 -0.3048)
						)
						(arc
							(start -0.2032 -0.3048)
							(mid -0.275042 -0.275042)
							(end -0.3048 -0.2032)
						)
						(arc
							(start -0.3048 0.2032)
							(mid -0.275042 0.275042)
							(end -0.2032 0.3048)
						)
						(arc
							(start 0.2032 0.3048)
							(mid 0.275042 0.275042)
							(end 0.3048 0.2032)
						)
					)
					(width 0)
					(fill yes)
				)
			)
		)
	)
	(footprint ""
		(layer "F.Cu")
		(at 234.315 -382.1938 180)
		(property "Reference" "R1153"
			(at 0 0 180)
			(layer "F.SilkS")
			(hide yes)
			(effects
				(font
					(size 1.27 1.27)
				)
			)
		)
		(property "Value" "10KR2F-2-GP"
			(at 0.064008 -3.993896 180)
			(unlocked yes)
			(layer "F.Fab")
			(hide yes)
			(effects
				(font
					(size 1.016 1.016)
					(thickness 0.1524)
				)
			)
		)
		(property "Device Type" "R402H16"
			(at 0.064008 -5.517896 180)
			(unlocked yes)
			(layer "F.Fab")
			(hide yes)
			(effects
				(font
					(size 1.016 1.016)
					(thickness 0.1524)
				)
			)
		)
		(duplicate_pad_numbers_are_jumpers no)
		(fp_line
			(start 0.508 -0.9398)
			(end -0.508 -0.9398)
			(stroke
				(width 0.1524)
				(type default)
			)
			(layer "F.SilkS")
		)
		(fp_line
			(start -0.508 -0.9398)
			(end -0.508 0.9398)
			(stroke
				(width 0.1524)
				(type default)
			)
			(layer "F.SilkS")
		)
		(fp_rect
			(start -0.508 0.9398)
			(end 0.508 -0.9398)
			(stroke
				(width 0)
				(type default)
			)
			(fill no)
			(layer "F.CrtYd")
		)
		(fp_rect
			(start -0.508 0.9398)
			(end 0.508 -0.9398)
			(stroke
				(width 0)
				(type default)
			)
			(fill no)
			(layer "F.Fab")
		)
		(pad "1" smd custom
			(at 0 -0.4445 180)
			(size 0.1397 0.1397)
			(layers "F.Cu" "F.Mask" "F.Paste")
			(net "P12V_A")
			(options
				(clearance outline)
				(anchor circle)
			)
			(primitives
				(gr_poly
					(pts
						(arc
							(start -0.1778 -0.2794)
							(mid -0.249642 -0.249642)
							(end -0.2794 -0.1778)
						)
						(arc
							(start -0.2794 0.1778)
							(mid -0.249642 0.249642)
							(end -0.1778 0.2794)
						)
						(arc
							(start 0.1778 0.2794)
							(mid 0.249642 0.249642)
							(end 0.2794 0.1778)
						)
						(arc
							(start 0.2794 -0.1778)
							(mid 0.249642 -0.249642)
							(end 0.1778 -0.2794)
						)
					)
					(width 0)
					(fill yes)
				)
			)
		)
		(pad "2" smd custom
			(at 0 0.4445 180)
			(size 0.1397 0.1397)
			(layers "F.Cu" "F.Mask" "F.Paste")
			(net "P12V_A_PGOOD")
			(options
				(clearance outline)
				(anchor circle)
			)
			(primitives
				(gr_poly
					(pts
						(arc
							(start -0.1778 -0.2794)
							(mid -0.249642 -0.249642)
							(end -0.2794 -0.1778)
						)
						(arc
							(start -0.2794 0.1778)
							(mid -0.249642 0.249642)
							(end -0.1778 0.2794)
						)
						(arc
							(start 0.1778 0.2794)
							(mid 0.249642 0.249642)
							(end 0.2794 0.1778)
						)
						(arc
							(start 0.2794 -0.1778)
							(mid 0.249642 -0.249642)
							(end 0.1778 -0.2794)
						)
					)
					(width 0)
					(fill yes)
				)
			)
		)
	)
	(footprint ""
		(layer "F.Cu")
		(at 44.1198 -143.129 90)
		(property "Reference" "C615"
			(at 0 0 90)
			(layer "F.SilkS")
			(hide yes)
			(effects
				(font
					(size 1.27 1.27)
				)
			)
		)
		(property "Value" "SC10U16V5KX-7-GP-U"
			(at -0.0762 -6.1214 90)
			(unlocked yes)
			(layer "F.Fab")
			(hide yes)
			(effects
				(font
					(size 1.016 1.016)
					(thickness 0.1524)
				)
			)
		)
		(property "Device Type" "C805H58"
			(at -0.0762 -8.1534 90)
			(unlocked yes)
			(layer "F.Fab")
			(hide yes)
			(effects
				(font
					(size 1.016 1.016)
					(thickness 0.1524)
				)
			)
		)
		(duplicate_pad_numbers_are_jumpers no)
		(fp_line
			(start 0.635 0)
			(end -0.635 0)
			(stroke
				(width 0.508)
				(type default)
			)
			(layer "F.SilkS")
		)
		(fp_rect
			(start -0.9652 1.778)
			(end 0.9652 -1.778)
			(stroke
				(width 0)
				(type default)
			)
			(fill no)
			(layer "F.CrtYd")
		)
		(fp_poly
			(pts
				(xy -0.9652 -1.778) (xy 0.9652 -1.778) (xy 0.9652 1.778) (xy -0.9652 1.778)
			)
			(stroke
				(width 0)
				(type default)
			)
			(fill no)
			(layer "F.Fab")
		)
		(pad "1" smd rect
			(at 0 -0.9652 90)
			(size 1.397 1.143)
			(layers "F.Cu" "F.Mask" "F.Paste")
			(net "P12V_A_VIN_U21")
		)
		(pad "2" smd rect
			(at 0 0.9652 90)
			(size 1.397 1.143)
			(layers "F.Cu" "F.Mask" "F.Paste")
			(net "GND")
		)
	)
	(footprint ""
		(layer "F.Cu")
		(at 149.549866 -145.372074 180)
		(property "Reference" "C547"
			(at 0 0 180)
			(layer "F.SilkS")
			(hide yes)
			(effects
				(font
					(size 1.27 1.27)
				)
			)
		)
		(property "Value" "SCD1U25V2KX-2-GP"
			(at 1.1811 -2.7051 180)
			(unlocked yes)
			(layer "F.Fab")
			(hide yes)
			(effects
				(font
					(size 1.016 1.016)
					(thickness 0.1524)
				)
			)
		)
		(property "Device Type" "C402H22"
			(at 1.1811 -4.2291 180)
			(unlocked yes)
			(layer "F.Fab")
			(hide yes)
			(effects
				(font
					(size 1.016 1.016)
					(thickness 0.1524)
				)
			)
		)
		(duplicate_pad_numbers_are_jumpers no)
		(fp_rect
			(start -0.4318 0.9525)
			(end 0.4318 -0.9525)
			(stroke
				(width 0)
				(type default)
			)
			(fill no)
			(layer "F.CrtYd")
		)
		(fp_rect
			(start -0.4318 0.9525)
			(end 0.4318 -0.9525)
			(stroke
				(width 0)
				(type default)
			)
			(fill no)
			(layer "F.Fab")
		)
		(pad "1" smd custom
			(at 0 -0.4445 180)
			(size 0.1524 0.1524)
			(layers "F.Cu" "F.Mask" "F.Paste")
			(net "MB0_PSET_R")
			(options
				(clearance outline)
				(anchor circle)
			)
			(primitives
				(gr_poly
					(pts
						(arc
							(start 0.3048 -0.2032)
							(mid 0.275042 -0.275042)
							(end 0.2032 -0.3048)
						)
						(arc
							(start -0.2032 -0.3048)
							(mid -0.275042 -0.275042)
							(end -0.3048 -0.2032)
						)
						(arc
							(start -0.3048 0.2032)
							(mid -0.275042 0.275042)
							(end -0.2032 0.3048)
						)
						(arc
							(start 0.2032 0.3048)
							(mid 0.275042 0.275042)
							(end 0.3048 0.2032)
						)
					)
					(width 0)
					(fill yes)
				)
			)
		)
		(pad "2" smd custom
			(at 0 0.4445 180)
			(size 0.1524 0.1524)
			(layers "F.Cu" "F.Mask" "F.Paste")
			(net "AGND_CURRENT_MONOA")
			(options
				(clearance outline)
				(anchor circle)
			)
			(primitives
				(gr_poly
					(pts
						(arc
							(start 0.3048 -0.2032)
							(mid 0.275042 -0.275042)
							(end 0.2032 -0.3048)
						)
						(arc
							(start -0.2032 -0.3048)
							(mid -0.275042 -0.275042)
							(end -0.3048 -0.2032)
						)
						(arc
							(start -0.3048 0.2032)
							(mid -0.275042 0.275042)
							(end -0.2032 0.3048)
						)
						(arc
							(start 0.2032 0.3048)
							(mid 0.275042 0.275042)
							(end 0.3048 0.2032)
						)
					)
					(width 0)
					(fill yes)
				)
			)
		)
	)
)
